FILE_TYPE = CONNECTIVITY;
{Allegro Design Entry HDL 17.2-2016 S081 (4005846) 1/11/2022}
"PAGE_NUMBER" = 87;
0"NC";
1"M_C_CPU0_SA_CB<7:0>";
2"M_C_CPU0_SA_CA<6:0>";
3"M_C_CPU0_SB_CA<6:0>";
4"M_C_CPU0_SB_CB<7:0>";
5"M_C_CPU0_SA_DQ<31:0>";
6"M_C_CPU0_SB_DQ<31:0>";
7"M_C_CPU0_SA_DQS_DN<9:0>";
8"M_C_CPU0_SA_DQS_DP<9:0>";
9"M_C_CPU0_SB_DQS_DN<9:0>";
10"M_C_CPU0_SB_DQS_DP<9:0>";
11"GND\g";
12"GND\g";
13"P3V3_STBY\g";
14"I3C_SPD_DDRAF_CPU0_SDA";
15"I3C_SPD_DDRC_CPU0_SCL";
16"I3C_SPD_DDRAF_CPU0_SCL";
17"PWRGD_CHC_CPU0_DIMM";
18"PD_CHC_CPU0_DIMM_SAA";
19"P3V3_STBY\g";
20"TP_CHC_CPU0_DIMM_RFU_5";
21"TP_CHC_CPU0_DIMM_RFU_4";
22"TP_CHC_CPU0_DIMM_RFU_3";
23"TP_CHC_CPU0_DIMM_RFU_6";
24"GND\g";
25"GND\g";
26"P12V_MEM_1\g";
27"GND\g";
28"M_C_CPU0_SB_DQS_DP<9>";
29"M_C_CPU0_SB_DQS_DN<9>";
30"M_C_CPU0_SA_DQS_DP<9>";
31"M_C_CPU0_SA_DQS_DN<9>";
32"M_C_CPU0_SA_DQS_DP<8>";
33"M_C_CPU0_SA_DQS_DN<8>";
34"M_C_CPU0_SB_DQS_DN<7>";
35"M_C_CPU0_SA_DQS_DP<7>";
36"M_C_CPU0_SB_DQS_DP<6>";
37"M_C_CPU0_SB_DQS_DN<6>";
38"M_C_CPU0_SA_DQS_DN<6>";
39"M_C_CPU0_SB_DQS_DP<5>";
40"M_C_CPU0_SB_DQS_DN<5>";
41"M_C_CPU0_SA_DQS_DP<5>";
42"M_C_CPU0_SA_DQS_DN<5>";
43"M_C_CPU0_SB_DQS_DP<4>";
44"M_C_CPU0_SB_DQS_DN<4>";
45"M_C_CPU0_SA_DQS_DP<4>";
46"M_C_CPU0_SA_DQS_DN<4>";
47"M_C_CPU0_SB_DQS_DP<3>";
48"M_C_CPU0_SB_DQS_DN<3>";
49"M_C_CPU0_SA_DQS_DP<3>";
50"M_C_CPU0_SA_DQS_DN<3>";
51"M_C_CPU0_SB_DQS_DP<2>";
52"M_C_CPU0_SB_DQS_DN<2>";
53"M_C_CPU0_SA_DQS_DP<2>";
54"M_C_CPU0_SA_DQS_DN<2>";
55"M_C_CPU0_SB_DQS_DP<1>";
56"M_C_CPU0_SB_DQS_DN<1>";
57"M_C_CPU0_SA_DQS_DP<1>";
58"M_C_CPU0_SA_DQS_DN<1>";
59"M_C_CPU0_SB_DQS_DP<0>";
60"M_C_CPU0_SB_DQS_DN<0>";
61"M_C_CPU0_SA_DQS_DP<0>";
62"M_C_CPU0_SA_DQS_DN<0>";
63"M_C_CPU0_SB_DQS_DP<7>";
64"M_C_CPU0_SB_DQS_DN<8>";
65"M_C_CPU0_SB_DQS_DP<8>";
66"M_C_CPU0_SA_DQS_DP<6>";
67"M_C_CPU0_SA_DQS_DN<7>";
68"M_C_CPU0_SA_DQ<20>";
69"M_C_CPU0_SA_DQ<21>";
70"M_C_CPU0_SA_DQ<22>";
71"M_C_CPU0_SA_DQ<23>";
72"M_C_CPU0_SA_DQ<24>";
73"M_C_CPU0_SA_DQ<27>";
74"M_C_CPU0_SA_DQ<28>";
75"TP_CHC_CPU0_DIMM_RFU_0";
76"TP_CHC_CPU0_DIMM_RFU_1";
77"TP_CHC_CPU0_DIMM_RFU_2";
78"M_C_CPU0_RESET_N";
79"M_C_CPU0_SB_PAR";
80"M_C_CPU0_SA_PAR";
81"M_C_CPU0_SB_RSP<0>";
82"M_C_CPU0_SA_RSP<0>";
83"M_C_CPU0_SB_DQ<0>";
84"M_C_CPU0_SB_DQ<1>";
85"M_C_CPU0_SB_DQ<2>";
86"M_C_CPU0_SB_DQ<3>";
87"M_C_CPU0_SB_DQ<4>";
88"M_C_CPU0_SB_DQ<5>";
89"M_C_CPU0_SB_DQ<6>";
90"M_C_CPU0_SB_DQ<7>";
91"M_C_CPU0_SB_DQ<8>";
92"M_C_CPU0_SB_DQ<9>";
93"M_C_CPU0_SB_DQ<10>";
94"M_C_CPU0_SB_DQ<11>";
95"M_C_CPU0_SB_DQ<12>";
96"M_C_CPU0_SB_DQ<13>";
97"M_C_CPU0_SB_DQ<14>";
98"M_C_CPU0_SB_DQ<15>";
99"M_C_CPU0_SB_DQ<16>";
100"M_C_CPU0_SB_DQ<17>";
101"M_C_CPU0_SB_DQ<18>";
102"M_C_CPU0_SB_DQ<19>";
103"M_C_CPU0_SB_DQ<20>";
104"M_C_CPU0_SB_DQ<21>";
105"M_C_CPU0_SB_DQ<22>";
106"M_C_CPU0_SB_DQ<23>";
107"M_C_CPU0_SB_DQ<24>";
108"M_C_CPU0_SB_DQ<25>";
109"M_C_CPU0_SB_DQ<26>";
110"M_C_CPU0_SB_DQ<27>";
111"M_C_CPU0_SB_DQ<28>";
112"M_C_CPU0_SB_DQ<29>";
113"M_C_CPU0_SB_DQ<30>";
114"M_C_CPU0_SB_DQ<31>";
115"M_C_CPU0_SA_DQ<0>";
116"M_C_CPU0_SA_DQ<1>";
117"M_C_CPU0_SA_DQ<2>";
118"M_C_CPU0_SA_DQ<3>";
119"M_C_CPU0_SA_DQ<4>";
120"M_C_CPU0_SA_DQ<5>";
121"M_C_CPU0_SA_DQ<6>";
122"M_C_CPU0_SA_DQ<7>";
123"M_C_CPU0_SA_DQ<8>";
124"M_C_CPU0_SA_DQ<9>";
125"M_C_CPU0_SA_DQ<10>";
126"M_C_CPU0_SA_DQ<11>";
127"M_C_CPU0_SA_DQ<12>";
128"M_C_CPU0_SA_DQ<13>";
129"M_C_CPU0_SA_DQ<14>";
130"M_C_CPU0_SA_DQ<15>";
131"M_C_CPU0_SA_DQ<16>";
132"M_C_CPU0_SA_DQ<17>";
133"M_C_CPU0_SA_DQ<18>";
134"M_C_CPU0_SA_DQ<19>";
135"M_C_CPU0_SA_DQ<25>";
136"M_C_CPU0_SA_DQ<26>";
137"M_C_CPU0_SA_DQ<29>";
138"M_C_CPU0_SA_DQ<30>";
139"M_C_CPU0_SB_CS_N<1>";
140"M_C_CPU0_SA_CS_N<1>";
141"M_C_CPU0_SB_CS_N<0>";
142"M_C_CPU0_SA_CS_N<0>";
143"M_C_CPU0_CLK_DP<0>";
144"M_C_CPU0_CLK_DN<0>";
145"M_C_CPU0_SB_CB<0>";
146"M_C_CPU0_SB_CB<1>";
147"M_C_CPU0_SB_CB<2>";
148"M_C_CPU0_SB_CB<3>";
149"M_C_CPU0_SB_CB<4>";
150"M_C_CPU0_SB_CB<5>";
151"M_C_CPU0_SB_CB<6>";
152"M_C_CPU0_SA_CB<0>";
153"M_C_CPU0_SA_CB<2>";
154"M_C_CPU0_SA_CB<3>";
155"M_C_CPU0_SA_CB<5>";
156"M_C_CPU0_SA_CB<6>";
157"M_C_CPU0_SB_CA<6>";
158"M_C_CPU0_SA_CA<6>";
159"M_C_CPU0_SB_CA<5>";
160"M_C_CPU0_SA_CA<5>";
161"M_C_CPU0_SB_CA<4>";
162"M_C_CPU0_SA_CA<4>";
163"M_C_CPU0_SB_CA<3>";
164"M_C_CPU0_SA_CA<3>";
165"M_C_CPU0_SB_CA<2>";
166"M_C_CPU0_SA_CA<2>";
167"M_C_CPU0_SB_CA<1>";
168"M_C_CPU0_SA_CA<1>";
169"M_C_CPU0_SB_CA<0>";
170"M_C_CPU0_SA_CA<0>";
171"M_C_CPU0_ALERT_N";
172"M_C_CPU0_SB_CB<7>";
173"M_C_CPU0_SA_CB<1>";
174"M_C_CPU0_SA_CB<4>";
175"M_C_CPU0_SA_CB<7>";
176"M_C_CPU0_SA_DQ<31>";
177"PWRGD_CHAF_CPU0";
178"PD_CHC_CPU0_DIMM_SAA";
%"GND"
"1","(-2300,2300)","0","mstr_symbols","I150";
;
SIZE"1B"
CDS_LIB"mstr_symbols"
BODY_TYPE"PLUMBING"
VOLTAGE"0.0"
HDL_POWER"GND";
"A\NAC"24;
%"GND"
"1","(-500,2100)","0","mstr_symbols","I152";
;
CDS_LIB"mstr_symbols"
SIZE"1B"
BODY_TYPE"PLUMBING"
VOLTAGE"0.0"
HDL_POWER"GND";
"A\NAC"27;
%"VCC_CORE"
"1","(-8800,3775)","0","mstr_symbols","I177";
;
HDL_POWER"P3V3_STBY"
CDS_LIB"mstr_symbols"
VOLTAGE"3.3"
ROOM"PVCCINFAON_CPU0_CTRL";
"A"19;
%"TAP"
"1","(-7925,3575)","2","mstr_standard","I187";
;
CDS_LIB"mstr_standard"
BODY_TYPE"PLUMBING"
HDL_TAP"TRUE";
"B \NAC \NWC"4;
"S \NAC"
BN"1"146;
%"TAP"
"1","(-7925,3625)","2","mstr_standard","I188";
;
CDS_LIB"mstr_standard"
BODY_TYPE"PLUMBING"
HDL_TAP"TRUE";
"B \NAC \NWC"4;
"S \NAC"
BN"2"147;
%"TAP"
"1","(-7925,3525)","2","mstr_standard","I189";
;
CDS_LIB"mstr_standard"
BODY_TYPE"PLUMBING"
HDL_TAP"TRUE";
"B \NAC \NWC"4;
"S \NAC"
BN"0"145;
%"TAP"
"1","(-7925,3675)","2","mstr_standard","I190";
;
CDS_LIB"mstr_standard"
BODY_TYPE"PLUMBING"
HDL_TAP"TRUE";
"B \NAC \NWC"4;
"S \NAC"
BN"3"148;
%"TAP"
"1","(-7925,3725)","2","mstr_standard","I191";
;
CDS_LIB"mstr_standard"
BODY_TYPE"PLUMBING"
HDL_TAP"TRUE";
"B \NAC \NWC"4;
"S \NAC"
BN"4"149;
%"TAP"
"1","(-7925,3775)","2","mstr_standard","I192";
;
CDS_LIB"mstr_standard"
BODY_TYPE"PLUMBING"
HDL_TAP"TRUE";
"B \NAC \NWC"4;
"S \NAC"
BN"5"150;
%"TAP"
"1","(-7925,3875)","2","mstr_standard","I193";
;
CDS_LIB"mstr_standard"
BODY_TYPE"PLUMBING"
HDL_TAP"TRUE";
"B \NAC \NWC"4;
"S \NAC"
BN"7"172;
%"TAP"
"1","(-7925,3825)","2","mstr_standard","I194";
;
CDS_LIB"mstr_standard"
BODY_TYPE"PLUMBING"
HDL_TAP"TRUE";
"B \NAC \NWC"4;
"S \NAC"
BN"6"151;
%"TAP"
"1","(-7925,4075)","2","mstr_standard","I195";
;
CDS_LIB"mstr_standard"
BODY_TYPE"PLUMBING"
HDL_TAP"TRUE";
"B \NAC \NWC"1;
"S \NAC"
BN"2"153;
%"TAP"
"1","(-7925,4025)","2","mstr_standard","I196";
;
CDS_LIB"mstr_standard"
BODY_TYPE"PLUMBING"
HDL_TAP"TRUE";
"B \NAC \NWC"1;
"S \NAC"
BN"1"173;
%"TAP"
"1","(-7925,3975)","2","mstr_standard","I197";
;
CDS_LIB"mstr_standard"
BODY_TYPE"PLUMBING"
HDL_TAP"TRUE";
"B \NAC \NWC"1;
"S \NAC"
BN"0"152;
%"TAP"
"1","(-7925,4125)","2","mstr_standard","I198";
;
CDS_LIB"mstr_standard"
BODY_TYPE"PLUMBING"
HDL_TAP"TRUE";
"B \NAC \NWC"1;
"S \NAC"
BN"3"154;
%"TAP"
"1","(-7925,4175)","2","mstr_standard","I199";
;
CDS_LIB"mstr_standard"
BODY_TYPE"PLUMBING"
HDL_TAP"TRUE";
"B \NAC \NWC"1;
"S \NAC"
BN"4"174;
%"TAP"
"1","(-7925,4225)","2","mstr_standard","I200";
;
CDS_LIB"mstr_standard"
BODY_TYPE"PLUMBING"
HDL_TAP"TRUE";
"B \NAC \NWC"1;
"S \NAC"
BN"5"155;
%"TAP"
"1","(-7925,4275)","2","mstr_standard","I201";
;
CDS_LIB"mstr_standard"
BODY_TYPE"PLUMBING"
HDL_TAP"TRUE";
"B \NAC \NWC"1;
"S \NAC"
BN"6"156;
%"TAP"
"1","(-7925,4325)","2","mstr_standard","I202";
;
CDS_LIB"mstr_standard"
BODY_TYPE"PLUMBING"
HDL_TAP"TRUE";
"B \NAC \NWC"1;
"S \NAC"
BN"7"175;
%"TAP"
"1","(-7925,5175)","2","mstr_standard","I203";
;
CDS_LIB"mstr_standard"
BODY_TYPE"PLUMBING"
HDL_TAP"TRUE";
"B \NAC \NWC"3;
"S \NAC"
BN"3"163;
%"TAP"
"1","(-7925,5075)","2","mstr_standard","I204";
;
CDS_LIB"mstr_standard"
BODY_TYPE"PLUMBING"
HDL_TAP"TRUE";
"B \NAC \NWC"3;
"S \NAC"
BN"1"167;
%"TAP"
"1","(-7925,5025)","2","mstr_standard","I205";
;
CDS_LIB"mstr_standard"
BODY_TYPE"PLUMBING"
HDL_TAP"TRUE";
"B \NAC \NWC"3;
"S \NAC"
BN"0"169;
%"TAP"
"1","(-7925,5125)","2","mstr_standard","I206";
;
CDS_LIB"mstr_standard"
BODY_TYPE"PLUMBING"
HDL_TAP"TRUE";
"B \NAC \NWC"3;
"S \NAC"
BN"2"165;
%"TAP"
"1","(-6225,2575)","0","mstr_standard","I207";
;
CDS_LIB"mstr_standard"
BODY_TYPE"PLUMBING"
HDL_TAP"TRUE";
"B \NAC \NWC"6;
"S \NAC"
BN"1"84;
%"TAP"
"1","(-6225,2525)","0","mstr_standard","I208";
;
CDS_LIB"mstr_standard"
BODY_TYPE"PLUMBING"
HDL_TAP"TRUE";
"B \NAC \NWC"6;
"S \NAC"
BN"0"83;
%"TAP"
"1","(-6225,2625)","0","mstr_standard","I209";
;
CDS_LIB"mstr_standard"
BODY_TYPE"PLUMBING"
HDL_TAP"TRUE";
"B \NAC \NWC"6;
"S \NAC"
BN"2"85;
%"TAP"
"1","(-6225,2675)","0","mstr_standard","I210";
;
CDS_LIB"mstr_standard"
BODY_TYPE"PLUMBING"
HDL_TAP"TRUE";
"B \NAC \NWC"6;
"S \NAC"
BN"3"86;
%"TAP"
"1","(-6225,2725)","0","mstr_standard","I211";
;
CDS_LIB"mstr_standard"
BODY_TYPE"PLUMBING"
HDL_TAP"TRUE";
"B \NAC \NWC"6;
"S \NAC"
BN"4"87;
%"TAP"
"1","(-6225,2775)","0","mstr_standard","I212";
;
CDS_LIB"mstr_standard"
BODY_TYPE"PLUMBING"
HDL_TAP"TRUE";
"B \NAC \NWC"6;
"S \NAC"
BN"5"88;
%"TAP"
"1","(-6225,2875)","0","mstr_standard","I213";
;
CDS_LIB"mstr_standard"
BODY_TYPE"PLUMBING"
HDL_TAP"TRUE";
"B \NAC \NWC"6;
"S \NAC"
BN"7"90;
%"TAP"
"1","(-6225,2825)","0","mstr_standard","I214";
;
CDS_LIB"mstr_standard"
BODY_TYPE"PLUMBING"
HDL_TAP"TRUE";
"B \NAC \NWC"6;
"S \NAC"
BN"6"89;
%"TAP"
"1","(-6225,2925)","0","mstr_standard","I215";
;
CDS_LIB"mstr_standard"
BODY_TYPE"PLUMBING"
HDL_TAP"TRUE";
"B \NAC \NWC"6;
"S \NAC"
BN"8"91;
%"TAP"
"1","(-6225,2975)","0","mstr_standard","I216";
;
CDS_LIB"mstr_standard"
BODY_TYPE"PLUMBING"
HDL_TAP"TRUE";
"B \NAC \NWC"6;
"S \NAC"
BN"9"92;
%"TAP"
"1","(-6225,3025)","0","mstr_standard","I217";
;
CDS_LIB"mstr_standard"
BODY_TYPE"PLUMBING"
HDL_TAP"TRUE";
"B \NAC \NWC"6;
"S \NAC"
BN"10"93;
%"TAP"
"1","(-6225,3075)","0","mstr_standard","I218";
;
CDS_LIB"mstr_standard"
BODY_TYPE"PLUMBING"
HDL_TAP"TRUE";
"B \NAC \NWC"6;
"S \NAC"
BN"11"94;
%"TAP"
"1","(-6225,3125)","0","mstr_standard","I219";
;
CDS_LIB"mstr_standard"
BODY_TYPE"PLUMBING"
HDL_TAP"TRUE";
"B \NAC \NWC"6;
"S \NAC"
BN"12"95;
%"TAP"
"1","(-6225,3175)","0","mstr_standard","I220";
;
CDS_LIB"mstr_standard"
BODY_TYPE"PLUMBING"
HDL_TAP"TRUE";
"B \NAC \NWC"6;
"S \NAC"
BN"13"96;
%"TAP"
"1","(-6225,3275)","0","mstr_standard","I221";
;
CDS_LIB"mstr_standard"
BODY_TYPE"PLUMBING"
HDL_TAP"TRUE";
"B \NAC \NWC"6;
"S \NAC"
BN"15"98;
%"TAP"
"1","(-6225,3225)","0","mstr_standard","I222";
;
CDS_LIB"mstr_standard"
BODY_TYPE"PLUMBING"
HDL_TAP"TRUE";
"B \NAC \NWC"6;
"S \NAC"
BN"14"97;
%"TAP"
"1","(-6225,3425)","0","mstr_standard","I223";
;
CDS_LIB"mstr_standard"
BODY_TYPE"PLUMBING"
HDL_TAP"TRUE";
"B \NAC \NWC"6;
"S \NAC"
BN"18"101;
%"TAP"
"1","(-6225,3375)","0","mstr_standard","I224";
;
CDS_LIB"mstr_standard"
BODY_TYPE"PLUMBING"
HDL_TAP"TRUE";
"B \NAC \NWC"6;
"S \NAC"
BN"17"100;
%"TAP"
"1","(-6225,3325)","0","mstr_standard","I225";
;
CDS_LIB"mstr_standard"
BODY_TYPE"PLUMBING"
HDL_TAP"TRUE";
"B \NAC \NWC"6;
"S \NAC"
BN"16"99;
%"TAP"
"1","(-6225,3575)","0","mstr_standard","I226";
;
CDS_LIB"mstr_standard"
BODY_TYPE"PLUMBING"
HDL_TAP"TRUE";
"B \NAC \NWC"6;
"S \NAC"
BN"21"104;
%"TAP"
"1","(-6225,3625)","0","mstr_standard","I227";
;
CDS_LIB"mstr_standard"
BODY_TYPE"PLUMBING"
HDL_TAP"TRUE";
"B \NAC \NWC"6;
"S \NAC"
BN"22"105;
%"TAP"
"1","(-6225,3525)","0","mstr_standard","I228";
;
CDS_LIB"mstr_standard"
BODY_TYPE"PLUMBING"
HDL_TAP"TRUE";
"B \NAC \NWC"6;
"S \NAC"
BN"20"103;
%"TAP"
"1","(-6225,3675)","0","mstr_standard","I229";
;
CDS_LIB"mstr_standard"
BODY_TYPE"PLUMBING"
HDL_TAP"TRUE";
"B \NAC \NWC"6;
"S \NAC"
BN"23"106;
%"TAP"
"1","(-6225,3475)","0","mstr_standard","I230";
;
CDS_LIB"mstr_standard"
BODY_TYPE"PLUMBING"
HDL_TAP"TRUE";
"B \NAC \NWC"6;
"S \NAC"
BN"19"102;
%"TAP"
"1","(-6225,3825)","0","mstr_standard","I231";
;
CDS_LIB"mstr_standard"
BODY_TYPE"PLUMBING"
HDL_TAP"TRUE";
"B \NAC \NWC"6;
"S \NAC"
BN"26"109;
%"TAP"
"1","(-6225,3875)","0","mstr_standard","I232";
;
CDS_LIB"mstr_standard"
BODY_TYPE"PLUMBING"
HDL_TAP"TRUE";
"B \NAC \NWC"6;
"S \NAC"
BN"27"110;
%"TAP"
"1","(-6225,3775)","0","mstr_standard","I233";
;
CDS_LIB"mstr_standard"
BODY_TYPE"PLUMBING"
HDL_TAP"TRUE";
"B \NAC \NWC"6;
"S \NAC"
BN"25"108;
%"TAP"
"1","(-6225,3925)","0","mstr_standard","I234";
;
CDS_LIB"mstr_standard"
BODY_TYPE"PLUMBING"
HDL_TAP"TRUE";
"B \NAC \NWC"6;
"S \NAC"
BN"28"111;
%"TAP"
"1","(-6225,3725)","0","mstr_standard","I235";
;
CDS_LIB"mstr_standard"
BODY_TYPE"PLUMBING"
HDL_TAP"TRUE";
"B \NAC \NWC"6;
"S \NAC"
BN"24"107;
%"TAP"
"1","(-6225,4175)","0","mstr_standard","I236";
;
CDS_LIB"mstr_standard"
BODY_TYPE"PLUMBING"
HDL_TAP"TRUE";
"B \NAC \NWC"5;
"S \NAC"
BN"0"115;
%"TAP"
"1","(-6225,4025)","0","mstr_standard","I237";
;
CDS_LIB"mstr_standard"
BODY_TYPE"PLUMBING"
HDL_TAP"TRUE";
"B \NAC \NWC"6;
"S \NAC"
BN"30"113;
%"TAP"
"1","(-6225,4075)","0","mstr_standard","I238";
;
CDS_LIB"mstr_standard"
BODY_TYPE"PLUMBING"
HDL_TAP"TRUE";
"B \NAC \NWC"6;
"S \NAC"
BN"31"114;
%"TAP"
"1","(-6225,3975)","0","mstr_standard","I239";
;
CDS_LIB"mstr_standard"
BODY_TYPE"PLUMBING"
HDL_TAP"TRUE";
"B \NAC \NWC"6;
"S \NAC"
BN"29"112;
%"TAP"
"1","(-6225,4275)","0","mstr_standard","I240";
;
CDS_LIB"mstr_standard"
BODY_TYPE"PLUMBING"
HDL_TAP"TRUE";
"B \NAC \NWC"5;
"S \NAC"
BN"2"117;
%"TAP"
"1","(-6225,4225)","0","mstr_standard","I241";
;
CDS_LIB"mstr_standard"
BODY_TYPE"PLUMBING"
HDL_TAP"TRUE";
"B \NAC \NWC"5;
"S \NAC"
BN"1"116;
%"TAP"
"1","(-6225,4325)","0","mstr_standard","I242";
;
CDS_LIB"mstr_standard"
BODY_TYPE"PLUMBING"
HDL_TAP"TRUE";
"B \NAC \NWC"5;
"S \NAC"
BN"3"118;
%"TAP"
"1","(-6225,4375)","0","mstr_standard","I243";
;
CDS_LIB"mstr_standard"
BODY_TYPE"PLUMBING"
HDL_TAP"TRUE";
"B \NAC \NWC"5;
"S \NAC"
BN"4"119;
%"TAP"
"1","(-6225,4425)","0","mstr_standard","I244";
;
CDS_LIB"mstr_standard"
BODY_TYPE"PLUMBING"
HDL_TAP"TRUE";
"B \NAC \NWC"5;
"S \NAC"
BN"5"120;
%"TAP"
"1","(-6225,4525)","0","mstr_standard","I245";
;
CDS_LIB"mstr_standard"
BODY_TYPE"PLUMBING"
HDL_TAP"TRUE";
"B \NAC \NWC"5;
"S \NAC"
BN"7"122;
%"TAP"
"1","(-6225,4475)","0","mstr_standard","I246";
;
CDS_LIB"mstr_standard"
BODY_TYPE"PLUMBING"
HDL_TAP"TRUE";
"B \NAC \NWC"5;
"S \NAC"
BN"6"121;
%"TAP"
"1","(-6225,4575)","0","mstr_standard","I247";
;
CDS_LIB"mstr_standard"
BODY_TYPE"PLUMBING"
HDL_TAP"TRUE";
"B \NAC \NWC"5;
"S \NAC"
BN"8"123;
%"TAP"
"1","(-6225,4625)","0","mstr_standard","I248";
;
CDS_LIB"mstr_standard"
BODY_TYPE"PLUMBING"
HDL_TAP"TRUE";
"B \NAC \NWC"5;
"S \NAC"
BN"9"124;
%"TAP"
"1","(-6225,4675)","0","mstr_standard","I249";
;
CDS_LIB"mstr_standard"
BODY_TYPE"PLUMBING"
HDL_TAP"TRUE";
"B \NAC \NWC"5;
"S \NAC"
BN"10"125;
%"TAP"
"1","(-6225,4875)","0","mstr_standard","I250";
;
CDS_LIB"mstr_standard"
BODY_TYPE"PLUMBING"
HDL_TAP"TRUE";
"B \NAC \NWC"5;
"S \NAC"
BN"14"129;
%"TAP"
"1","(-6225,4925)","0","mstr_standard","I251";
;
CDS_LIB"mstr_standard"
BODY_TYPE"PLUMBING"
HDL_TAP"TRUE";
"B \NAC \NWC"5;
"S \NAC"
BN"15"130;
%"TAP"
"1","(-6225,4825)","0","mstr_standard","I252";
;
CDS_LIB"mstr_standard"
BODY_TYPE"PLUMBING"
HDL_TAP"TRUE";
"B \NAC \NWC"5;
"S \NAC"
BN"13"128;
%"TAP"
"1","(-6225,4775)","0","mstr_standard","I253";
;
CDS_LIB"mstr_standard"
BODY_TYPE"PLUMBING"
HDL_TAP"TRUE";
"B \NAC \NWC"5;
"S \NAC"
BN"12"127;
%"TAP"
"1","(-6225,4725)","0","mstr_standard","I254";
;
CDS_LIB"mstr_standard"
BODY_TYPE"PLUMBING"
HDL_TAP"TRUE";
"B \NAC \NWC"5;
"S \NAC"
BN"11"126;
%"TAP"
"1","(-6225,5025)","0","mstr_standard","I255";
;
CDS_LIB"mstr_standard"
BODY_TYPE"PLUMBING"
HDL_TAP"TRUE";
"B \NAC \NWC"5;
"S \NAC"
BN"17"132;
%"TAP"
"1","(-6225,5075)","0","mstr_standard","I256";
;
CDS_LIB"mstr_standard"
BODY_TYPE"PLUMBING"
HDL_TAP"TRUE";
"B \NAC \NWC"5;
"S \NAC"
BN"18"133;
%"TAP"
"1","(-6225,4975)","0","mstr_standard","I257";
;
CDS_LIB"mstr_standard"
BODY_TYPE"PLUMBING"
HDL_TAP"TRUE";
"B \NAC \NWC"5;
"S \NAC"
BN"16"131;
%"TAP"
"1","(-6225,5175)","0","mstr_standard","I258";
;
CDS_LIB"mstr_standard"
BODY_TYPE"PLUMBING"
HDL_TAP"TRUE";
"B \NAC \NWC"5;
"S \NAC"
BN"20"68;
%"TAP"
"1","(-6225,5125)","0","mstr_standard","I259";
;
CDS_LIB"mstr_standard"
BODY_TYPE"PLUMBING"
HDL_TAP"TRUE";
"B \NAC \NWC"5;
"S \NAC"
BN"19"134;
%"TAP"
"1","(-7925,5325)","2","mstr_standard","I263";
;
CDS_LIB"mstr_standard"
BODY_TYPE"PLUMBING"
HDL_TAP"TRUE";
"B \NAC \NWC"3;
"S \NAC"
BN"6"157;
%"TAP"
"1","(-7925,5225)","2","mstr_standard","I264";
;
CDS_LIB"mstr_standard"
BODY_TYPE"PLUMBING"
HDL_TAP"TRUE";
"B \NAC \NWC"3;
"S \NAC"
BN"4"161;
%"TAP"
"1","(-7925,5275)","2","mstr_standard","I265";
;
CDS_LIB"mstr_standard"
BODY_TYPE"PLUMBING"
HDL_TAP"TRUE";
"B \NAC \NWC"3;
"S \NAC"
BN"5"159;
%"TAP"
"1","(-7925,5425)","2","mstr_standard","I266";
;
CDS_LIB"mstr_standard"
BODY_TYPE"PLUMBING"
HDL_TAP"TRUE";
"B \NAC \NWC"2;
"S \NAC"
BN"0"170;
%"TAP"
"1","(-7925,5475)","2","mstr_standard","I267";
;
CDS_LIB"mstr_standard"
BODY_TYPE"PLUMBING"
HDL_TAP"TRUE";
"B \NAC \NWC"2;
"S \NAC"
BN"1"168;
%"TAP"
"1","(-7925,5525)","2","mstr_standard","I268";
;
CDS_LIB"mstr_standard"
BODY_TYPE"PLUMBING"
HDL_TAP"TRUE";
"B \NAC \NWC"2;
"S \NAC"
BN"2"166;
%"TAP"
"1","(-7925,5575)","2","mstr_standard","I269";
;
CDS_LIB"mstr_standard"
BODY_TYPE"PLUMBING"
HDL_TAP"TRUE";
"B \NAC \NWC"2;
"S \NAC"
BN"3"164;
%"TAP"
"1","(-7925,5675)","2","mstr_standard","I270";
;
CDS_LIB"mstr_standard"
BODY_TYPE"PLUMBING"
HDL_TAP"TRUE";
"B \NAC \NWC"2;
"S \NAC"
BN"5"160;
%"TAP"
"1","(-7925,5625)","2","mstr_standard","I271";
;
CDS_LIB"mstr_standard"
BODY_TYPE"PLUMBING"
HDL_TAP"TRUE";
"B \NAC \NWC"2;
"S \NAC"
BN"4"162;
%"TAP"
"1","(-7925,5725)","2","mstr_standard","I272";
;
CDS_LIB"mstr_standard"
BODY_TYPE"PLUMBING"
HDL_TAP"TRUE";
"B \NAC \NWC"2;
"S \NAC"
BN"6"158;
%"TAP"
"1","(-6225,5325)","0","mstr_standard","I273";
;
CDS_LIB"mstr_standard"
BODY_TYPE"PLUMBING"
HDL_TAP"TRUE";
"B \NAC \NWC"5;
"S \NAC"
BN"23"71;
%"TAP"
"1","(-6225,5225)","0","mstr_standard","I274";
;
CDS_LIB"mstr_standard"
BODY_TYPE"PLUMBING"
HDL_TAP"TRUE";
"B \NAC \NWC"5;
"S \NAC"
BN"21"69;
%"TAP"
"1","(-6225,5275)","0","mstr_standard","I275";
;
CDS_LIB"mstr_standard"
BODY_TYPE"PLUMBING"
HDL_TAP"TRUE";
"B \NAC \NWC"5;
"S \NAC"
BN"22"70;
%"TAP"
"1","(-6225,5375)","0","mstr_standard","I276";
;
CDS_LIB"mstr_standard"
BODY_TYPE"PLUMBING"
HDL_TAP"TRUE";
"B \NAC \NWC"5;
"S \NAC"
BN"24"72;
%"TAP"
"1","(-6225,5425)","0","mstr_standard","I277";
;
CDS_LIB"mstr_standard"
BODY_TYPE"PLUMBING"
HDL_TAP"TRUE";
"B \NAC \NWC"5;
"S \NAC"
BN"25"135;
%"TAP"
"1","(-6225,5475)","0","mstr_standard","I278";
;
CDS_LIB"mstr_standard"
BODY_TYPE"PLUMBING"
HDL_TAP"TRUE";
"B \NAC \NWC"5;
"S \NAC"
BN"26"136;
%"TAP"
"1","(-6225,5725)","0","mstr_standard","I279";
;
CDS_LIB"mstr_standard"
BODY_TYPE"PLUMBING"
HDL_TAP"TRUE";
"B \NAC \NWC"5;
"S \NAC"
BN"31"176;
%"TAP"
"1","(-6225,5525)","0","mstr_standard","I280";
;
CDS_LIB"mstr_standard"
BODY_TYPE"PLUMBING"
HDL_TAP"TRUE";
"B \NAC \NWC"5;
"S \NAC"
BN"27"73;
%"TAP"
"1","(-6225,5575)","0","mstr_standard","I281";
;
CDS_LIB"mstr_standard"
BODY_TYPE"PLUMBING"
HDL_TAP"TRUE";
"B \NAC \NWC"5;
"S \NAC"
BN"28"74;
%"TAP"
"1","(-6225,5675)","0","mstr_standard","I282";
;
CDS_LIB"mstr_standard"
BODY_TYPE"PLUMBING"
HDL_TAP"TRUE";
"B \NAC \NWC"5;
"S \NAC"
BN"30"138;
%"TAP"
"1","(-6225,5625)","0","mstr_standard","I283";
;
CDS_LIB"mstr_standard"
BODY_TYPE"PLUMBING"
HDL_TAP"TRUE";
"B \NAC \NWC"5;
"S \NAC"
BN"29"137;
%"GND"
"1","(-6625,1350)","0","mstr_symbols","I332";
;
BOM_COST"MEM"
CDS_LIB"mstr_symbols"
SIZE"1B"
BODY_TYPE"PLUMBING"
VOLTAGE"0.0"
HDL_POWER"GND";
"A\NAC"11;
%"Q_RES"
"2","(-6625,1575)","0","pure_quanta","I349";
;
LOCATION"R762"
$SEC"1"
CDS_SEC"1"
WATTAGE"1/16W"
MATERIAL"CHIP"
TOLERANCE"1%"
VALUE"23.2K"
PART_NUMBER"TMP_QCS32322FB11"
PACK_TYPE"0402LF"
CDS_LIB"pure_quanta";
"A"
$PN"1"178;
"B"
$PN"2"11;
%"SCONN288_DDR506112002KQ"
"1","(-7075,3975)","0","pure_quanta","I350";
;
LOCATION"J17"
$SEC"1"
CDS_SEC"1"
VALUE"SCONN288_DDR506112002KQ"
PART_TYPE"SMLF"
MATERIAL"IO"
PART_NUMBER"DFHST8FS479"
CDS_LMAN_SYM_OUTLINE"-450,1900,450,-1850"
NEEDS_NO_SIZE"TRUE"
CDS_LIB"pure_quanta";
"PWR_GOOD||FAIL_N"
$PN"147"17;
"DQ31_A"
$PN"194"176;
"CB7_A"
$PN"205"175;
"CB4_A"
$PN"58"174;
"CB1_A"
$PN"53"173;
"CB7_B"
$PN"236"172;
"ALERT_N \B"
$PN"62"171;
"CA0_A"
$PN"66"170;
"CA0_B"
$PN"76"169;
"CA1_A"
$PN"211"168;
"CA1_B"
$PN"221"167;
"CA2_A"
$PN"68"166;
"CA2_B"
$PN"78"165;
"CA3_A"
$PN"213"164;
"CA3_B"
$PN"223"163;
"CA4_A"
$PN"70"162;
"CA4_B"
$PN"80"161;
"CA5_A"
$PN"215"160;
"CA5_B"
$PN"225"159;
"CA6_A"
$PN"72"158;
"CA6_B"
$PN"82"157;
"CB6_A"
$PN"203"156;
"CB5_A"
$PN"60"155;
"CB3_A"
$PN"198"154;
"CB2_A"
$PN"196"153;
"CB0_A"
$PN"51"152;
"CB6_B"
$PN"234"151;
"CB5_B"
$PN"91"150;
"CB4_B"
$PN"89"149;
"CB3_B"
$PN"243"148;
"CB2_B"
$PN"241"147;
"CB1_B"
$PN"98"146;
"CB0_B"
$PN"96"145;
"CK_C \B"
$PN"218"144;
"CK_T"
$PN"217"143;
"CS0_A_N"
$PN"64"142;
"CS0_B_N"
$PN"84"141;
"CS1_A_N"
$PN"209"140;
"CS1_B_N"
$PN"229"139;
"DQ30_A"
$PN"192"138;
"DQ29_A"
$PN"49"137;
"DQ28_A"
$PN"47"74;
"DQ27_A"
$PN"187"73;
"DQ26_A"
$PN"185"136;
"DQ25_A"
$PN"42"135;
"DQ24_A"
$PN"40"72;
"DQ23_A"
$PN"183"71;
"DQ22_A"
$PN"181"70;
"DQ21_A"
$PN"38"69;
"DQ20_A"
$PN"36"68;
"DQ19_A"
$PN"176"134;
"DQ18_A"
$PN"174"133;
"DQ17_A"
$PN"31"132;
"DQ16_A"
$PN"29"131;
"DQ15_A"
$PN"172"130;
"DQ14_A"
$PN"170"129;
"DQ13_A"
$PN"27"128;
"DQ12_A"
$PN"25"127;
"DQ11_A"
$PN"165"126;
"DQ10_A"
$PN"163"125;
"DQ9_A"
$PN"20"124;
"DQ8_A"
$PN"18"123;
"DQ7_A"
$PN"161"122;
"DQ6_A"
$PN"159"121;
"DQ5_A"
$PN"16"120;
"DQ4_A"
$PN"14"119;
"DQ3_A"
$PN"154"118;
"DQ2_A"
$PN"152"117;
"DQ1_A"
$PN"9"116;
"DQ0_A"
$PN"7"115;
"DQ31_B"
$PN"287"114;
"DQ30_B"
$PN"285"113;
"DQ29_B"
$PN"142"112;
"DQ28_B"
$PN"140"111;
"DQ27_B"
$PN"280"110;
"DQ26_B"
$PN"278"109;
"DQ25_B"
$PN"135"108;
"DQ24_B"
$PN"133"107;
"DQ23_B"
$PN"276"106;
"DQ22_B"
$PN"274"105;
"DQ21_B"
$PN"131"104;
"DQ20_B"
$PN"129"103;
"DQ19_B"
$PN"269"102;
"DQ18_B"
$PN"267"101;
"DQ17_B"
$PN"124"100;
"DQ16_B"
$PN"122"99;
"DQ15_B"
$PN"265"98;
"DQ14_B"
$PN"263"97;
"DQ13_B"
$PN"120"96;
"DQ12_B"
$PN"118"95;
"DQ11_B"
$PN"258"94;
"DQ10_B"
$PN"256"93;
"DQ9_B"
$PN"113"92;
"DQ8_B"
$PN"111"91;
"DQ7_B"
$PN"254"90;
"DQ6_B"
$PN"252"89;
"DQ5_B"
$PN"109"88;
"DQ4_B"
$PN"107"87;
"DQ3_B"
$PN"247"86;
"DQ2_B"
$PN"245"85;
"DQ1_B"
$PN"102"84;
"DQ0_B"
$PN"100"83;
"HAS"
$PN"148"18;
"HSCL"
$PN"4"15;
"HSDA"
$PN"5"14;
"LBD||RSP_A_N"
$PN"86"82;
"LBS||RSP_B_N"
$PN"87"81;
"PAR_A"
$PN"74"80;
"PAR_B"
$PN"227"79;
"RESET_N \B"
$PN"207"78;
"RFU6"
$PN"232"23;
"RFU5"
$PN"231"20;
"RFU4"
$PN"220"21;
"RFU3"
$PN"150"22;
"RFU2"
$PN"149"77;
"RFU1"
$PN"144"76;
"RFU0"
$PN"2"75;
"VIN_MGMT"
$PN"3"19;
%"SCONN288_DDR506112002KQ"
"3","(-1400,4050)","0","pure_quanta","I352";
;
LOCATION"J17"
$SEC"3"
CDS_SEC"3"
PART_TYPE"SMLF"
VALUE"SCONN288_DDR506112002KQ"
MATERIAL"IO"
PART_NUMBER"DFHST8FS479"
CDS_LMAN_SYM_OUTLINE"-450,1800,450,-1750"
NEEDS_NO_SIZE"TRUE"
CDS_LIB"pure_quanta";
"G3"
$PN"G3"27;
"G2"
$PN"G2"27;
"G1"
$PN"G1"27;
"VSS62"
$PN"141"27;
"VSS61"
$PN"139"27;
"VSS60"
$PN"136"27;
"VSS58"
$PN"132"27;
"VSS104"
$PN"240"24;
"VSS102"
$PN"235"24;
"VSS100"
$PN"230"24;
"VIN_BULK2"
$PN"146"26;
"VIN_BULK1"
$PN"145"26;
"VIN_BULK0"
$PN"1"26;
"VSS126"
$PN"288"24;
"VSS125"
$PN"286"24;
"VSS124"
$PN"284"24;
"VSS123"
$PN"281"24;
"VSS122"
$PN"279"24;
"VSS121"
$PN"277"24;
"VSS120"
$PN"275"24;
"VSS119"
$PN"273"24;
"VSS118"
$PN"270"24;
"VSS117"
$PN"268"24;
"VSS116"
$PN"266"24;
"VSS115"
$PN"264"24;
"VSS114"
$PN"262"24;
"VSS113"
$PN"259"24;
"VSS112"
$PN"257"24;
"VSS111"
$PN"255"24;
"VSS110"
$PN"253"24;
"VSS109"
$PN"251"24;
"VSS108"
$PN"248"24;
"VSS107"
$PN"246"24;
"VSS106"
$PN"244"24;
"VSS105"
$PN"242"24;
"VSS103"
$PN"237"24;
"VSS101"
$PN"233"24;
"VSS99"
$PN"228"24;
"VSS98"
$PN"226"24;
"VSS97"
$PN"224"24;
"VSS96"
$PN"222"24;
"VSS95"
$PN"219"24;
"VSS94"
$PN"216"24;
"VSS93"
$PN"214"24;
"VSS92"
$PN"212"24;
"VSS91"
$PN"210"24;
"VSS90"
$PN"208"24;
"VSS89"
$PN"206"24;
"VSS88"
$PN"204"24;
"VSS87"
$PN"202"24;
"VSS86"
$PN"199"24;
"VSS85"
$PN"197"24;
"VSS84"
$PN"195"24;
"VSS83"
$PN"193"24;
"VSS82"
$PN"191"24;
"VSS81"
$PN"188"24;
"VSS80"
$PN"186"24;
"VSS79"
$PN"184"24;
"VSS78"
$PN"182"24;
"VSS77"
$PN"180"24;
"VSS76"
$PN"177"24;
"VSS75"
$PN"175"24;
"VSS74"
$PN"173"24;
"VSS73"
$PN"171"24;
"VSS72"
$PN"169"24;
"VSS71"
$PN"166"24;
"VSS70"
$PN"164"24;
"VSS69"
$PN"162"24;
"VSS68"
$PN"160"24;
"VSS67"
$PN"158"24;
"VSS66"
$PN"155"24;
"VSS65"
$PN"153"24;
"VSS64"
$PN"151"24;
"VSS63"
$PN"143"27;
"VSS59"
$PN"134"27;
"VSS57"
$PN"130"27;
"VSS56"
$PN"128"27;
"VSS55"
$PN"125"27;
"VSS54"
$PN"123"27;
"VSS53"
$PN"121"27;
"VSS52"
$PN"119"27;
"VSS51"
$PN"117"27;
"VSS50"
$PN"114"27;
"VSS49"
$PN"112"27;
"VSS48"
$PN"110"27;
"VSS47"
$PN"108"27;
"VSS46"
$PN"106"27;
"VSS45"
$PN"103"27;
"VSS44"
$PN"101"27;
"VSS43"
$PN"99"27;
"VSS42"
$PN"97"27;
"VSS41"
$PN"95"27;
"VSS40"
$PN"92"27;
"VSS39"
$PN"90"27;
"VSS38"
$PN"88"27;
"VSS37"
$PN"85"27;
"VSS36"
$PN"83"27;
"VSS35"
$PN"81"27;
"VSS34"
$PN"79"27;
"VSS33"
$PN"77"27;
"VSS32"
$PN"75"27;
"VSS31"
$PN"73"27;
"VSS30"
$PN"71"27;
"VSS29"
$PN"69"27;
"VSS28"
$PN"67"27;
"VSS27"
$PN"65"27;
"VSS26"
$PN"63"27;
"VSS25"
$PN"61"27;
"VSS24"
$PN"59"27;
"VSS23"
$PN"57"27;
"VSS22"
$PN"54"27;
"VSS21"
$PN"52"27;
"VSS20"
$PN"50"27;
"VSS19"
$PN"48"27;
"VSS18"
$PN"46"27;
"VSS17"
$PN"43"27;
"VSS16"
$PN"41"27;
"VSS15"
$PN"39"27;
"VSS14"
$PN"37"27;
"VSS13"
$PN"35"27;
"VSS12"
$PN"32"27;
"VSS11"
$PN"30"27;
"VSS10"
$PN"28"27;
"VSS9"
$PN"26"27;
"VSS8"
$PN"24"27;
"VSS7"
$PN"21"27;
"VSS6"
$PN"19"27;
"VSS5"
$PN"17"27;
"VSS4"
$PN"15"27;
"VSS3"
$PN"13"27;
"VSS2"
$PN"10"27;
"VSS1"
$PN"8"27;
"VSS0"
$PN"6"27;
%"GND"
"1","(-8925,3300)","0","mstr_symbols","I361";
;
BOM_COST"MEM"
SIZE"1B"
CDS_LIB"mstr_symbols"
BODY_TYPE"PLUMBING"
VOLTAGE"0"
ROOM"MEM_EFGH_DECOUPLING_CAPS"
HDL_POWER"GND";
"A\NAC"12;
%"Q_CAP"
"1","(-8925,3525)","2","pure_quanta","I362";
;
LOCATION"C96"
$SEC"1"
CDS_SEC"1"
TOLERANCE"10%"
VALUE"0.1UF"
PART_NUMBER"CH4104K1B00"
VOLTAGE"25V"
PACK_TYPE"0402"
MATERIAL"X7R"
BOM_COST"MEM"
CDS_LIB"pure_quanta"
ROOM"MEM_CH_A_CPU0_DIMM1";
"B"
$PN"2"12;
"A"
$PN"1"19;
%"Q_RES"
"1","(-8675,2475)","2","pure_quanta","I364";
;
LOCATION"R293"
$SEC"1"
CDS_SEC"1"
VALUE"0"
BOM_COST"MEM"
CDS_LIB"pure_quanta"
WATTAGE"1/16W"
MATERIAL"CHIP"
TOLERANCE"5%"
PART_NUMBER"CS00002JB38"
PACK_TYPE"0402LF"
ROOM"RST_CPU0_PLD_TO_DIMM";
"B"
$PN"2"177;
"A"
$PN"1"17;
%"Q_RES"
"2","(-8550,2625)","0","pure_quanta","I365";
;
LOCATION"R91"
$SEC"1"
CDS_SEC"1"
PACK_TYPE"0402LF"
VALUE"1K"
TOLERANCE"5%"
WATTAGE"1/16W"
MATERIAL"EMPTY"
CDS_LIB"pure_quanta"
BOM_COST"MEM"
PART_NUMBER"TMP_QCS21002JB34"
ROOM"MEM_CH_A_CPU0_DIMM1";
"A"
$PN"1"13;
"B"
$PN"2"17;
%"VCC_CORE"
"1","(-8550,2800)","0","mstr_symbols","I366";
;
HDL_POWER"P3V3_STBY"
CDS_LIB"mstr_symbols"
VOLTAGE"3.3"
ROOM"PVCCINFAON_CPU0_CTRL";
"A"13;
%"TAP"
"1","(-3525,4900)","0","mstr_standard","I371";
;
CDS_LIB"mstr_standard"
BODY_TYPE"PLUMBING"
HDL_TAP"TRUE";
"B \NAC \NWC"7;
"S \NAC"
BN"9"31;
%"TAP"
"1","(-3525,4700)","0","mstr_standard","I372";
;
CDS_LIB"mstr_standard"
BODY_TYPE"PLUMBING"
HDL_TAP"TRUE";
"B \NAC \NWC"7;
"S \NAC"
BN"7"67;
%"TAP"
"1","(-3525,4800)","0","mstr_standard","I373";
;
CDS_LIB"mstr_standard"
BODY_TYPE"PLUMBING"
HDL_TAP"TRUE";
"B \NAC \NWC"7;
"S \NAC"
BN"8"33;
%"TAP"
"1","(-3525,4600)","0","mstr_standard","I374";
;
CDS_LIB"mstr_standard"
BODY_TYPE"PLUMBING"
HDL_TAP"TRUE";
"B \NAC \NWC"7;
"S \NAC"
BN"6"38;
%"TAP"
"1","(-3525,4500)","0","mstr_standard","I375";
;
CDS_LIB"mstr_standard"
BODY_TYPE"PLUMBING"
HDL_TAP"TRUE";
"B \NAC \NWC"7;
"S \NAC"
BN"5"42;
%"TAP"
"1","(-3525,4400)","0","mstr_standard","I376";
;
CDS_LIB"mstr_standard"
BODY_TYPE"PLUMBING"
HDL_TAP"TRUE";
"B \NAC \NWC"7;
"S \NAC"
BN"4"46;
%"TAP"
"1","(-3525,4300)","0","mstr_standard","I377";
;
CDS_LIB"mstr_standard"
BODY_TYPE"PLUMBING"
HDL_TAP"TRUE";
"B \NAC \NWC"7;
"S \NAC"
BN"3"50;
%"TAP"
"1","(-3525,4200)","0","mstr_standard","I378";
;
CDS_LIB"mstr_standard"
BODY_TYPE"PLUMBING"
HDL_TAP"TRUE";
"B \NAC \NWC"7;
"S \NAC"
BN"2"54;
%"TAP"
"1","(-3525,4100)","0","mstr_standard","I379";
;
CDS_LIB"mstr_standard"
BODY_TYPE"PLUMBING"
HDL_TAP"TRUE";
"B \NAC \NWC"7;
"S \NAC"
BN"1"58;
%"TAP"
"1","(-3525,4000)","0","mstr_standard","I380";
;
CDS_LIB"mstr_standard"
BODY_TYPE"PLUMBING"
HDL_TAP"TRUE";
"B \NAC \NWC"7;
"S \NAC"
BN"0"62;
%"TAP"
"1","(-3525,3850)","0","mstr_standard","I381";
;
CDS_LIB"mstr_standard"
BODY_TYPE"PLUMBING"
HDL_TAP"TRUE";
"B \NAC \NWC"9;
"S \NAC"
BN"9"29;
%"TAP"
"1","(-3525,3750)","0","mstr_standard","I382";
;
CDS_LIB"mstr_standard"
BODY_TYPE"PLUMBING"
HDL_TAP"TRUE";
"B \NAC \NWC"9;
"S \NAC"
BN"8"64;
%"TAP"
"1","(-3525,3550)","0","mstr_standard","I383";
;
CDS_LIB"mstr_standard"
BODY_TYPE"PLUMBING"
HDL_TAP"TRUE";
"B \NAC \NWC"9;
"S \NAC"
BN"6"37;
%"TAP"
"1","(-3525,3650)","0","mstr_standard","I384";
;
CDS_LIB"mstr_standard"
BODY_TYPE"PLUMBING"
HDL_TAP"TRUE";
"B \NAC \NWC"9;
"S \NAC"
BN"7"34;
%"TAP"
"1","(-3525,3450)","0","mstr_standard","I385";
;
CDS_LIB"mstr_standard"
BODY_TYPE"PLUMBING"
HDL_TAP"TRUE";
"B \NAC \NWC"9;
"S \NAC"
BN"5"40;
%"TAP"
"1","(-3525,3350)","0","mstr_standard","I386";
;
CDS_LIB"mstr_standard"
BODY_TYPE"PLUMBING"
HDL_TAP"TRUE";
"B \NAC \NWC"9;
"S \NAC"
BN"4"44;
%"TAP"
"1","(-3525,3150)","0","mstr_standard","I387";
;
CDS_LIB"mstr_standard"
BODY_TYPE"PLUMBING"
HDL_TAP"TRUE";
"B \NAC \NWC"9;
"S \NAC"
BN"2"52;
%"TAP"
"1","(-3525,3250)","0","mstr_standard","I388";
;
CDS_LIB"mstr_standard"
BODY_TYPE"PLUMBING"
HDL_TAP"TRUE";
"B \NAC \NWC"9;
"S \NAC"
BN"3"48;
%"TAP"
"1","(-3525,3050)","0","mstr_standard","I389";
;
CDS_LIB"mstr_standard"
BODY_TYPE"PLUMBING"
HDL_TAP"TRUE";
"B \NAC \NWC"9;
"S \NAC"
BN"1"56;
%"TAP"
"1","(-3525,2950)","0","mstr_standard","I390";
;
CDS_LIB"mstr_standard"
BODY_TYPE"PLUMBING"
HDL_TAP"TRUE";
"B \NAC \NWC"9;
"S \NAC"
BN"0"60;
%"TAP"
"1","(-3725,4950)","0","mstr_standard","I391";
;
CDS_LIB"mstr_standard"
BODY_TYPE"PLUMBING"
HDL_TAP"TRUE";
"B \NAC \NWC"8;
"S \NAC"
BN"9"30;
%"TAP"
"1","(-3725,4850)","0","mstr_standard","I392";
;
CDS_LIB"mstr_standard"
BODY_TYPE"PLUMBING"
HDL_TAP"TRUE";
"B \NAC \NWC"8;
"S \NAC"
BN"8"32;
%"TAP"
"1","(-3725,4750)","0","mstr_standard","I393";
;
CDS_LIB"mstr_standard"
BODY_TYPE"PLUMBING"
HDL_TAP"TRUE";
"B \NAC \NWC"8;
"S \NAC"
BN"7"35;
%"TAP"
"1","(-3725,4550)","0","mstr_standard","I394";
;
CDS_LIB"mstr_standard"
BODY_TYPE"PLUMBING"
HDL_TAP"TRUE";
"B \NAC \NWC"8;
"S \NAC"
BN"5"41;
%"TAP"
"1","(-3725,4650)","0","mstr_standard","I395";
;
CDS_LIB"mstr_standard"
BODY_TYPE"PLUMBING"
HDL_TAP"TRUE";
"B \NAC \NWC"8;
"S \NAC"
BN"6"66;
%"TAP"
"1","(-3725,4450)","0","mstr_standard","I396";
;
CDS_LIB"mstr_standard"
BODY_TYPE"PLUMBING"
HDL_TAP"TRUE";
"B \NAC \NWC"8;
"S \NAC"
BN"4"45;
%"TAP"
"1","(-3725,4350)","0","mstr_standard","I397";
;
CDS_LIB"mstr_standard"
BODY_TYPE"PLUMBING"
HDL_TAP"TRUE";
"B \NAC \NWC"8;
"S \NAC"
BN"3"49;
%"TAP"
"1","(-3725,4250)","0","mstr_standard","I398";
;
CDS_LIB"mstr_standard"
BODY_TYPE"PLUMBING"
HDL_TAP"TRUE";
"B \NAC \NWC"8;
"S \NAC"
BN"2"53;
%"TAP"
"1","(-3725,4050)","0","mstr_standard","I399";
;
CDS_LIB"mstr_standard"
BODY_TYPE"PLUMBING"
HDL_TAP"TRUE";
"B \NAC \NWC"8;
"S \NAC"
BN"0"61;
%"TAP"
"1","(-3725,4150)","0","mstr_standard","I400";
;
CDS_LIB"mstr_standard"
BODY_TYPE"PLUMBING"
HDL_TAP"TRUE";
"B \NAC \NWC"8;
"S \NAC"
BN"1"57;
%"TAP"
"1","(-3725,3800)","0","mstr_standard","I401";
;
CDS_LIB"mstr_standard"
BODY_TYPE"PLUMBING"
HDL_TAP"TRUE";
"B \NAC \NWC"10;
"S \NAC"
BN"8"65;
%"TAP"
"1","(-3725,3900)","0","mstr_standard","I402";
;
CDS_LIB"mstr_standard"
BODY_TYPE"PLUMBING"
HDL_TAP"TRUE";
"B \NAC \NWC"10;
"S \NAC"
BN"9"28;
%"TAP"
"1","(-3725,3700)","0","mstr_standard","I403";
;
CDS_LIB"mstr_standard"
BODY_TYPE"PLUMBING"
HDL_TAP"TRUE";
"B \NAC \NWC"10;
"S \NAC"
BN"7"63;
%"TAP"
"1","(-3725,3600)","0","mstr_standard","I404";
;
CDS_LIB"mstr_standard"
BODY_TYPE"PLUMBING"
HDL_TAP"TRUE";
"B \NAC \NWC"10;
"S \NAC"
BN"6"36;
%"TAP"
"1","(-3725,3500)","0","mstr_standard","I405";
;
CDS_LIB"mstr_standard"
BODY_TYPE"PLUMBING"
HDL_TAP"TRUE";
"B \NAC \NWC"10;
"S \NAC"
BN"5"39;
%"TAP"
"1","(-3725,3400)","0","mstr_standard","I406";
;
CDS_LIB"mstr_standard"
BODY_TYPE"PLUMBING"
HDL_TAP"TRUE";
"B \NAC \NWC"10;
"S \NAC"
BN"4"43;
%"TAP"
"1","(-3725,3300)","0","mstr_standard","I407";
;
CDS_LIB"mstr_standard"
BODY_TYPE"PLUMBING"
HDL_TAP"TRUE";
"B \NAC \NWC"10;
"S \NAC"
BN"3"47;
%"TAP"
"1","(-3725,3200)","0","mstr_standard","I408";
;
CDS_LIB"mstr_standard"
BODY_TYPE"PLUMBING"
HDL_TAP"TRUE";
"B \NAC \NWC"10;
"S \NAC"
BN"2"51;
%"TAP"
"1","(-3725,3100)","0","mstr_standard","I409";
;
CDS_LIB"mstr_standard"
BODY_TYPE"PLUMBING"
HDL_TAP"TRUE";
"B \NAC \NWC"10;
"S \NAC"
BN"1"55;
%"TAP"
"1","(-3725,3000)","0","mstr_standard","I410";
;
CDS_LIB"mstr_standard"
BODY_TYPE"PLUMBING"
HDL_TAP"TRUE";
"B \NAC \NWC"10;
"S \NAC"
BN"0"59;
%"SCONN288_DDR506112002KQ"
"2","(-4675,3950)","0","pure_quanta","I411";
;
LOCATION"J17"
$SEC"2"
CDS_SEC"2"
MATERIAL"IO"
PART_TYPE"SMLF"
VALUE"SCONN288_DDR506112002KQ"
PART_NUMBER"DFHST8FS479"
CDS_LMAN_SYM_OUTLINE"-600,1150,600,-1150"
NEEDS_NO_SIZE"TRUE"
CDS_LIB"pure_quanta";
"DQS7_A_C||TDQS7_A_C \B"
$PN"178"67;
"DQS6_A_T||TDQS6_A_T"
$PN"168"66;
"DQS8_B_T||TDQS8_B_T"
$PN"283"65;
"DQS8_B_C||TDQS8_B_C \B"
$PN"282"64;
"DQS7_B_T||TDQS7_B_T"
$PN"272"63;
"DQS0_A_C \B"
$PN"12"62;
"DQS0_A_T"
$PN"11"61;
"DQS0_B_C \B"
$PN"105"60;
"DQS0_B_T"
$PN"104"59;
"DQS1_A_C \B"
$PN"23"58;
"DQS1_A_T"
$PN"22"57;
"DQS1_B_C \B"
$PN"116"56;
"DQS1_B_T"
$PN"115"55;
"DQS2_A_C \B"
$PN"34"54;
"DQS2_A_T"
$PN"33"53;
"DQS2_B_C \B"
$PN"127"52;
"DQS2_B_T"
$PN"126"51;
"DQS3_A_C \B"
$PN"45"50;
"DQS3_A_T"
$PN"44"49;
"DQS3_B_C \B"
$PN"138"48;
"DQS3_B_T"
$PN"137"47;
"DQS4_A_C \B"
$PN"56"46;
"DQS4_A_T"
$PN"55"45;
"DQS4_B_C \B"
$PN"238"44;
"DQS4_B_T"
$PN"239"43;
"DQS5_A_C||TDQS5_A_C||DQS5_A_T||TDQS5_A_T \B"
$PN"156"42;
"DQS5_A_T||TDQS5_A_T"
$PN"157"41;
"DQS5_B_C||TDQS5_B_C \B"
$PN"249"40;
"DQS5_B_T||TDQS5_B_T"
$PN"250"39;
"DQS6_A_C||TDQS6_A_C||DQS6_A_T||TDQS6_A_T \B"
$PN"167"38;
"DQS6_B_C||TDQS6_B_C \B"
$PN"260"37;
"DQS6_B_T||TDQS6_B_T"
$PN"261"36;
"DQS7_A_T||TDQS7_A_T"
$PN"179"35;
"DQS7_B_C||TDQS7_B_C \B"
$PN"271"34;
"DQS8_A_C||TDQS8_A_C \B"
$PN"189"33;
"DQS8_A_T||TDQS8_A_T"
$PN"190"32;
"DQS9_A_C||TDQS9_A_C \B"
$PN"200"31;
"DQS9_A_T||TDQS9_A_T"
$PN"201"30;
"DQS9_B_C||TDQS9_B_C \B"
$PN"94"29;
"DQS9_B_T||TDQS9_B_T||DBI4_B_N"
$PN"93"28;
%"GND"
"1","(-3000,5800)","0","pure_quanta_power","I412";
;
CDS_LIB"pure_quanta_power"
BOM_COST"MEM"
SIZE"1B"
ROOM"MEM_EFGH_DECOUPLING_CAPS"
HDL_POWER"GND";
"A<SIZE-1..0>\NAC"25;
%"Q_CAP"
"1","(-3000,6150)","2","pure_quanta","I413";
;
LOCATION"C146"
$SEC"1"
CDS_SEC"1"
MATERIAL"X6S"
TOLERANCE"10%"
VALUE"10UF"
PART_NUMBER"CH6104KEA00"
VOLTAGE"25V"
PACK_TYPE"C0805"
BOM_COST"MEM"
CDS_LIB"pure_quanta"
ROOM"MEM_CH_A_CPU0_DIMM1";
"B"
$PN"2"25;
"A"
$PN"1"26;
%"Q_CAP"
"1","(-2425,6150)","2","pure_quanta","I414";
;
LOCATION"C147"
$SEC"1"
CDS_SEC"1"
MATERIAL"X6S"
TOLERANCE"10%"
VALUE"10UF"
PART_NUMBER"CH6104KEA00"
VOLTAGE"25V"
PACK_TYPE"C0805"
BOM_COST"MEM"
CDS_LIB"pure_quanta"
ROOM"MEM_CH_A_CPU0_DIMM1";
"B"
$PN"2"25;
"A"
$PN"1"26;
%"UNIVERSAL_POWER"
"1","(-3000,6475)","0","pure_quanta_power","I415";
;
HDL_POWER"P12V_MEM_1"
BOM_COST"VR_SYSTEM"
CDS_LIB"pure_quanta_power";
"A"26;
%"Q_RES"
"1","(-7950,3025)","0","pure_quanta","I417";
;
$LOCATION"R1570"
CDS_LOCATION"R1570"
$SEC"1"
CDS_SEC"1"
VALUE"49.9"
CDS_LIB"pure_quanta"
MATERIAL"CHIP"
PACK_TYPE"0402LF"
WATTAGE"1/16W"
TOLERANCE"1%"
PART_NUMBER"CS04992FB07";
"B"
$PN"2"15;
"A"
$PN"1"16;
END.
